FILE_TYPE = CONNECTIVITY;
{Allegro Design Entry HDL 16.6-p007 (v16-6-112F) 10/10/2012}
"PAGE_NUMBER" = 196;
0"NC";
1"GND\g";
2"GND\g";
3"P3V3_STBY\g";
4"P5V\g";
5"P12V\g";
6"GND\g";
7"GND\g";
8"P3V3_STBY\g";
9"GND\g";
10"P3V3_STBY\g";
11"P3V3_STBY\g";
12"GND\g";
13"GND\g";
14"P3V3_STBY\g";
15"P3V3_STBY\g";
16"P12V_STBY\g";
17"P3V3_STBY\g";
18"GND\g";
19"GND\g";
20"P3V3_STBY\g";
21"GND\g";
22"GND\g";
23"GND\g";
24"P3V3\g";
25"GND\g";
26"P3V3_RTC_STBY\g";
27"PWRGD_P3V3_STBY";
28"VSENSE_P12V_ADM1085";
29"P3V_BAT_SOURCE"CDS_PHYS_NET_NAME"P3V_BAT_SOURCE"VOLTAGE"+3 V";
30"PWRGD_P3V3";
31"PWRGD_P5V";
32"A_ADM1085_CEXT";
33"PWRGD_DSW_PWROK";
34"PWRGD_P5V_R";
35"PWRGD_P12V_MAIN";
36"PWRGD_P12V_HSC_DLY_R";
37"PWRGD_P3V3_R1";
38"A_P3V_BAT_R"VOLTAGE"+3 V"CDS_PHYS_NET_NAME"P3V_BAT_R";
39"PWRGD_P12V_HSC_DLY";
40"PWRGD_P12V_MAIN_R";
41"PWRGD_P5V_N";
42"A_PG_P5V";
43"A_PG_P12V_MAIN";
44"PWRGD_P12V_HSC";
%"CAP_A"
"1","(-2200,4500)","0","dev_discrete","I102";
;
TOLERANCE"10%"
NO_XNET_CONNECTION"1"
VOLTAGE"6.3V"
PACK_TYPE"0402V"
VALUE"1.0UF"
LOCATION"C2U26"
MATERIAL"X6S"
PART_NUMBER"D97712-004"
CDS_LIB"dev_discrete"
CDS_LOCATION"C2U26"
SEC"1"
BOM_COST"SB"
CDS_SEC"1"
ROOM"SB_VRD"
SEC_TYPE"0402V";
"B"
$PN"2"12;
"A"
$PN"1"26;
%"DIODE"
"3","(825,3650)","0","mstr_discrete","I103";
;
CDS_SEC"1"
PACK_TYPE"SMLF"
VALUE"BAT54WS"
MATERIAL"IC"
LOCATION"CR7E1"
PART_NUMBER"C73510-001"
CDS_LOCATION"CR7E1"
SEC"1"
SEC_TYPE"SMLF"
CDS_LIB"mstr_discrete";
"C"
$PN"1"27;
"A"
$PN"2"33;
%"TPS3700"
"1","(-500,2300)","0","mstr_vreg","I104";
;
CDS_LOCATION"U8D8"
MATERIAL"IC"
LOCATION"U8D8"
PART_NUMBER"H69492-001"
ROOM"V_SUPER"
$SEC"1"
CDS_SEC"1"
PACK_TYPE"SM"
CDS_LIB"mstr_vreg"
CDS_LMAN_SYM_OUTLINE"-250,200,250,-200";
"VDD"
$PN"2"3;
"OUTB"
$PN"1"41;
"OUTA"
$PN"6"40;
"INBN"
$PN"3"42;
"INAP"
$PN"4"43;
"GND"
$PN"5"1;
%"CAP_A"
"1","(-1000,1950)","0","dev_discrete","I105";
;
CDS_SEC"1"
$SEC"1"
CDS_LOCATION"C8D4"
MATERIAL"X7R"
VOLTAGE"16V"
LOCATION"C8D4"
TOLERANCE"10%"
VALUE"0.1UF"
PART_NUMBER"A36096-030"
PACK_TYPE"0402V"
CDS_LIB"dev_discrete"
ROOM"V_SUPER";
"B"
$PN"2"2;
"A"
$PN"1"3;
%"RES"
"1","(1350,2400)","0","mstr_discrete","I106";
;
CDS_SEC"1"
CDS_LOCATION"R8D42"
WATTAGE"1/16W"
VALUE"100.0"
MATERIAL"CHIP"
TOLERANCE"1%"
LOCATION"R8D42"
PART_NUMBER"G21796-017"
PACK_TYPE"0402"
CDS_LIB"mstr_discrete"
ROOM"V_SUPER"
SEC_TYPE"0402"
SEC"1";
"B"
$PN"2"35;
"A"
$PN"1"40;
%"GND"
"1","(-150,2000)","0","mstr_symbols","I108";
;
CDS_LIB"mstr_symbols"
SIZE"1B"
VOLTAGE"0.0V"
BODY_TYPE"PLUMBING"
HDL_POWER"GND";
"A\NAC"1;
%"GND"
"1","(-1000,1750)","0","mstr_symbols","I110";
;
VOLTAGE"0.0V"
CDS_LIB"mstr_symbols"
SIZE"1B"
BODY_TYPE"PLUMBING"
HDL_POWER"GND";
"A\NAC"2;
%"P3V3_STBY"
"1","(-1000,2750)","0","mstr_symbols","I111";
;
VOLTAGE"3.3V"
SIZE"1B"
CDS_LIB"mstr_symbols"
BODY_TYPE"PLUMBING"
HDL_POWER"P3V3_STBY";
"G\NAC"3;
%"RES"
"2","(-1750,2850)","0","mstr_discrete","I112";
;
CDS_SEC"1"
CDS_LOCATION"R8D38"
PACK_TYPE"0402"
TOLERANCE"1%"
LOCATION"R8D38"
WATTAGE"1/16W"
NEW_VALUE"511K"
CONFIG"64.51135.6DL"
MATERIAL"CHIP"
CDS_LIB"mstr_discrete"
ROOM"V_SUPER"
SEC_TYPE"0402"
SEC"1"
VALUE"100.0K"
PART_NUMBER"G21796-010";
"A"
$PN"1"5;
"B"
$PN"2"43;
%"RES"
"2","(-1750,1850)","0","mstr_discrete","I114";
;
CDS_SEC"1"
CDS_LOCATION"R8D39"
MATERIAL"CHIP"
PART_NUMBER"G21796-048"
PACK_TYPE"0402"
TOLERANCE"1%"
VALUE"49.9K"
LOCATION"R8D39"
WATTAGE"1/16W"
CDS_LIB"mstr_discrete"
ROOM"V_SUPER"
SEC_TYPE"0402"
SEC"1";
"A"
$PN"1"4;
"B"
$PN"2"42;
%"RES"
"2","(-1750,1450)","0","mstr_discrete","I115";
;
CDS_SEC"1"
CDS_LOCATION"R8D37"
TOLERANCE"1%"
MATERIAL"CHIP"
VALUE"4.75K"
LOCATION"R8D37"
PART_NUMBER"G21796-072"
PACK_TYPE"0402"
WATTAGE"1/16W"
CDS_LIB"mstr_discrete"
ROOM"V_SUPER"
SEC_TYPE"0402"
SEC"1";
"A"
$PN"1"42;
"B"
$PN"2"7;
%"P5V"
"1","(-1750,2050)","0","mstr_symbols","I116";
;
VOLTAGE"5.0V"
CDS_LIB"mstr_symbols"
SIZE"1B"
BODY_TYPE"PLUMBING"
HDL_POWER"P5V";
"G\NAC"4;
%"P12V"
"1","(-1750,3050)","0","mstr_symbols","I117";
;
SIZE"1B"
CDS_LIB"mstr_symbols"
VOLTAGE"12.0V"
BODY_TYPE"PLUMBING"
HDL_POWER"P12V";
"G\NAC"5;
%"GND"
"1","(-1750,2175)","0","mstr_symbols","I118";
;
CDS_LIB"mstr_symbols"
SIZE"1B"
VOLTAGE"0.0V"
BODY_TYPE"PLUMBING"
HDL_POWER"GND";
"A\NAC"6;
%"GND"
"1","(-1750,1250)","0","mstr_symbols","I119";
;
VOLTAGE"0.0V"
SIZE"1B"
CDS_LIB"mstr_symbols"
BODY_TYPE"PLUMBING"
HDL_POWER"GND";
"A\NAC"7;
%"RES"
"2","(50,2650)","0","mstr_discrete","I120";
;
CDS_SEC"1"
CDS_LOCATION"R8D41"
PACK_TYPE"0402"
PART_NUMBER"G21796-016"
LOCATION"R8D41"
VALUE"10.0K"
TOLERANCE"1%"
MATERIAL"CHIP"
WATTAGE"1/16W"
CDS_LIB"mstr_discrete"
ROOM"V_SUPER"
SEC_TYPE"0402"
SEC"1";
"A"
$PN"1"8;
"B"
$PN"2"40;
%"RES"
"2","(250,2000)","0","mstr_discrete","I121";
;
CDS_SEC"1"
CDS_LOCATION"R2P18"
WATTAGE"1/16W"
MATERIAL"CHIP"
PACK_TYPE"0402"
LOCATION"R2P18"
VALUE"10.0K"
TOLERANCE"1%"
PART_NUMBER"G21796-016"
CDS_LIB"mstr_discrete"
ROOM"V_SUPER"
SEC_TYPE"0402"
SEC"1";
"A"
$PN"1"10;
"B"
$PN"2"41;
%"RES"
"2","(750,2200)","0","mstr_discrete","I122";
;
CDS_SEC"1"
CDS_LOCATION"R2P21"
PACK_TYPE"0402"
WATTAGE"1/16W"
MATERIAL"CHIP"
VALUE"10.0K"
PART_NUMBER"G21796-016"
LOCATION"R2P21"
TOLERANCE"1%"
CDS_LIB"mstr_discrete"
ROOM"V_SUPER"
SEC"1"
SEC_TYPE"0402";
"A"
$PN"1"11;
"B"
$PN"2"34;
%"P3V3_STBY"
"1","(50,2850)","0","mstr_symbols","I123";
;
VOLTAGE"3.3V"
SIZE"1B"
CDS_LIB"mstr_symbols"
BODY_TYPE"PLUMBING"
HDL_POWER"P3V3_STBY";
"G\NAC"8;
%"GND"
"1","(750,1450)","0","mstr_symbols","I125";
;
SIZE"1B"
CDS_LIB"mstr_symbols"
VOLTAGE"0.0V"
BODY_TYPE"PLUMBING"
HDL_POWER"GND";
"A\NAC"9;
%"P3V3_STBY"
"1","(250,2300)","0","mstr_symbols","I126";
;
VOLTAGE"3.3V"
CDS_LIB"mstr_symbols"
SIZE"1B"
BODY_TYPE"PLUMBING"
HDL_POWER"P3V3_STBY";
"G\NAC"10;
%"P3V3_STBY"
"1","(750,2600)","0","mstr_symbols","I127";
;
VOLTAGE"3.3V"
CDS_LIB"mstr_symbols"
SIZE"1B"
BODY_TYPE"PLUMBING"
HDL_POWER"P3V3_STBY";
"G\NAC"11;
%"DIODE"
"3","(1050,3400)","0","mstr_discrete","I128";
;
CDS_SEC"1"
CDS_LOCATION"CR8E1"
LOCATION"CR8E1"
VALUE"BAT54WS"
PACK_TYPE"SMLF"
MATERIAL"IC"
PART_NUMBER"C73510-001"
CDS_LIB"mstr_discrete"
SEC_TYPE"SMLF"
SEC"1";
"C"
$PN"1"44;
"A"
$PN"2"39;
%"FET_N"
"8","(750,1750)","0","mstr_discrete","I129";
;
CDS_SEC"1"
$SEC"1"
CDS_LOCATION"Q1P2"
MATERIAL"FET"
LOCATION"Q1P2"
VALUE"2N7002"
PART_NUMBER"C79254-001"
PACK_TYPE"SOT23LF"
ROOM"HOT_SWAP"
CDS_LIB"mstr_discrete";
"GATE"
$PN"1"41;
"DRN"
$PN"3"34;
"SRC"
$PN"2"9;
%"RES"
"2","(-1750,2400)","0","mstr_discrete","I130";
;
CDS_SEC"1"
TOLERANCE"1%"
VALUE"20.0K"
MATERIAL"CHIP"
WATTAGE"1/16W"
PACK_TYPE"0402"
PART_NUMBER"G21796-040"
LOCATION"R8D40"
ROOM"SB"
BOM_COST"SB"
CDS_LIB"mstr_discrete"
SEC_TYPE"0402"
SEC"1"
CDS_LOCATION"R8D40";
"A"
$PN"1"43;
"B"
$PN"2"6;
%"GND"
"1","(-2200,4250)","0","mstr_symbols","I43";
;
ROOM"BATTERY_CIRCUIT"
CDS_LIB"mstr_symbols"
SIZE"1B"
VOLTAGE"0"
BODY_TYPE"PLUMBING"
HDL_POWER"GND";
"A\NAC"12;
%"RES"
"1","(-3650,4550)","0","mstr_discrete","I46";
;
CDS_SEC"1"
WATTAGE"1/16W"
TOLERANCE"1%"
VALUE"1.00K"
MATERIAL"CHIP"
PART_NUMBER"G21796-026"
PACK_TYPE"0402"
LOCATION"R2U43"
CDS_LIB"mstr_discrete"
CDS_LOCATION"R2U43"
BOM_COST"SB"
SEC_TYPE"0402"
SEC"1"
ROOM"SB_VRD";
"B"
$PN"2"38;
"A"
$PN"1"29;
%"BATTERY"
"1","(-4375,4200)","0","mstr_misc","I47";
;
PART_NUMBER"202168-001"
LOCATION"BT8G1"
BOM_COST"SB"
CDS_LIB"mstr_misc"
CDS_LOCATION"BT8G1"
PACK_TYPE"PLCLF"
ROOM"SB_VRD";
%"VERT_BATT_3PIN"
"1","(-4800,4550)","0","mstr_discrete","I51";
;
CDS_SEC"1"
PART_NUMBER"C68619-005"
MATERIAL"3PVERT"
LOCATION"XBT8G1"
CDS_LIB"mstr_discrete"
ROOM"SB_VRD"
SEC_TYPE"PIP"
SEC"1"
CDS_LOCATION"XBT8G1"
PACK_TYPE"PIP";
"P1\NAC"
$PN"1"29;
"P2\NAC"
$PN"2"29;
"N\NAC"
$PN"3"13;
%"GND"
"1","(-5050,4250)","0","mstr_symbols","I52";
;
ROOM"SB"
SIZE"1B"
VOLTAGE"0"
CDS_LIB"mstr_symbols"
BODY_TYPE"PLUMBING"
HDL_POWER"GND";
"A\NAC"13;
%"DIODE2A_DUAL"
"1","(-2700,4650)","0","mstr_discrete","I53";
;
CDS_SEC"1"
LOCATION"CR2U1"
MATERIAL"DIO"
PACK_TYPE"SMLF"
VALUE"BAS70-05"
PART_NUMBER"C90169-001"
SEC_TYPE"SMLF"
SEC"1"
CDS_LOCATION"CR2U1"
ROOM"SB_VRD"
CDS_LIB"mstr_discrete";
"C"
$PN"3"26;
"A1"
$PN"1"14;
"A2"
$PN"2"38;
%"P3V3_STBY"
"1","(-3250,4975)","0","mstr_symbols","I54";
;
VOLTAGE"3.3V"
SIZE"1B"
CDS_LIB"mstr_symbols"
BODY_TYPE"PLUMBING"
HDL_POWER"P3V3_STBY";
"G\NAC"14;
%"P3V3_STBY"
"1","(-25,5000)","0","mstr_symbols","I56";
;
CDS_LIB"mstr_symbols"
VOLTAGE"3.3V"
SIZE"1B"
BODY_TYPE"PLUMBING"
HDL_POWER"P3V3_STBY";
"G\NAC"15;
%"P12V_STBY"
"1","(-525,5000)","0","mstr_symbols","I57";
;
CDS_LIB"mstr_symbols"
VOLTAGE"12.0V"
SIZE"1B"
BODY_TYPE"PLUMBING"
HDL_POWER"P12V_STBY";
"G\NAC"16;
%"P3V3_STBY"
"1","(1325,4900)","0","mstr_symbols","I58";
;
VOLTAGE"3.3V"
SIZE"1B"
CDS_LIB"mstr_symbols"
BODY_TYPE"PLUMBING"
HDL_POWER"P3V3_STBY";
"G\NAC"17;
%"RES"
"2","(1325,4650)","0","mstr_discrete","I59";
;
CDS_SEC"1"
PACK_TYPE"0402"
MATERIAL"CHIP"
LOCATION"R3P44"
TOLERANCE"1%"
VALUE"4.75K"
WATTAGE"1/16W"
PART_NUMBER"G21796-072"
CDS_LIB"mstr_discrete"
CDS_LOCATION"R3P44"
ROOM"V_SUPER"
SEC_TYPE"0402"
SEC"1";
"A"
$PN"1"17;
"B"
$PN"2"33;
%"CAP"
"1","(1225,4050)","0","mstr_discrete","I60";
;
CDS_SEC"1"
MATERIAL"X7R"
PACK_TYPE"0402"
TOLERANCE"10%"
VALUE"0.047UF"
LOCATION"C3P45"
PART_NUMBER"A36096-090"
VOLTAGE"25V"
CDS_LIB"mstr_discrete"
ROOM"V_SUPER"
SEC_TYPE"0402"
SEC"1"
CDS_LOCATION"C3P45";
"A"
$PN"1"32;
"B"
$PN"2"19;
%"GND"
"1","(1125,4100)","0","mstr_symbols","I61";
;
VOLTAGE"0.0V"
SIZE"1B"
CDS_LIB"mstr_symbols"
BODY_TYPE"PLUMBING"
HDL_POWER"GND";
"A\NAC"18;
%"GND"
"1","(1225,3850)","0","mstr_symbols","I62";
;
VOLTAGE"0.0V"
CDS_LIB"mstr_symbols"
SIZE"1B"
BODY_TYPE"PLUMBING"
HDL_POWER"GND";
"A\NAC"19;
%"RES"
"1","(1350,2000)","0","mstr_discrete","I65";
;
CDS_SEC"1"
CDS_LOCATION"R2P20"
WATTAGE"1/16W"
VALUE"100.0"
PACK_TYPE"0402"
LOCATION"R2P20"
PART_NUMBER"G21796-017"
TOLERANCE"1%"
MATERIAL"CHIP"
CDS_LIB"mstr_discrete"
ROOM"V_SUPER"
SEC_TYPE"0402"
SEC"1";
"B"
$PN"2"31;
"A"
$PN"1"34;
%"RES"
"1","(1300,1250)","0","mstr_discrete","I68";
;
CDS_SEC"1"
WATTAGE"1/16W"
VALUE"49.9"
LOCATION"R1L16"
MATERIAL"CHIP"
TOLERANCE"1%"
PACK_TYPE"0402"
PART_NUMBER"G21796-047"
ROOM"V_SUPER"
CDS_LOCATION"R1L16"
SEC"1"
SEC_TYPE"0402"
CDS_LIB"mstr_discrete";
"B"
$PN"2"30;
"A"
$PN"1"37;
%"P3V3_STBY"
"1","(275,4900)","0","mstr_symbols","I69";
;
VOLTAGE"3.3V"
CDS_LIB"mstr_symbols"
SIZE"1B"
BODY_TYPE"PLUMBING"
HDL_POWER"P3V3_STBY";
"G\NAC"20;
%"ADM1085"
"1","(725,4400)","0","mstr_analog","I70";
;
CDS_SEC"1"
MATERIAL"IC"
LOCATION"U7D3"
PART_NUMBER"H46130-001"
ROOM"V_SUPER"
CDS_LOCATION"U7D3"
SEC"1"
SEC_TYPE"SMT"
PACK_TYPE"SMT"
CDS_LIB"mstr_analog";
"VIN"
$PN"3"28;
"VCC"
$PN"6"20;
"CEXT"
$PN"5"32;
"GND"
$PN"2"18;
"ENOUT"
$PN"4"33;
"ENIN"
$PN"1"27;
%"RES"
"2","(-25,4750)","0","mstr_discrete","I71";
;
CDS_SEC"1"
PACK_TYPE"0402"
TOLERANCE"1%"
WATTAGE"1/16W"
VALUE"10.0K"
MATERIAL"EMPTY"
LOCATION"R3P50"
PART_NUMBER"G21796-016"
CDS_LIB"mstr_discrete"
ROOM"V_SUPER"
SEC_TYPE"0402"
SEC"1"
CDS_LOCATION"R3P50";
"A"
$PN"1"15;
"B"
$PN"2"27;
%"CAP_A"
"1","(275,3950)","0","dev_discrete","I72";
;
CDS_SEC"1"
PACK_TYPE"0402V"
MATERIAL"X7R"
VOLTAGE"16V"
TOLERANCE"10%"
VALUE"0.1UF"
LOCATION"C3P46"
PART_NUMBER"A36096-030"
CDS_LIB"dev_discrete"
CDS_LOCATION"C3P46"
ROOM"V_SUPER"
SEC_TYPE"0402V"
SEC"1";
"B"
$PN"2"21;
"A"
$PN"1"20;
%"GND"
"1","(275,3750)","0","mstr_symbols","I73";
;
VOLTAGE"0.0V"
CDS_LIB"mstr_symbols"
SIZE"1B"
BODY_TYPE"PLUMBING"
HDL_POWER"GND";
"A\NAC"21;
%"RES"
"2","(-525,4750)","0","mstr_discrete","I74";
;
CDS_SEC"1"
PACK_TYPE"0402"
WATTAGE"1/16W"
MATERIAL"CHIP"
TOLERANCE"1%"
VALUE"90.9K"
LOCATION"R3P48"
PART_NUMBER"G21796-058"
CDS_LIB"mstr_discrete"
ROOM"V_SUPER"
SEC_TYPE"0402"
SEC"1"
CDS_LOCATION"R3P48";
"A"
$PN"1"16;
"B"
$PN"2"28;
%"RES"
"2","(-525,4250)","0","mstr_discrete","I75";
;
CDS_SEC"1"
LOCATION"R3P51"
VALUE"6.34K"
TOLERANCE"1%"
WATTAGE"1/16W"
PART_NUMBER"G21796-146"
PACK_TYPE"0402"
MATERIAL"CHIP"
CDS_LIB"mstr_discrete"
CDS_LOCATION"R3P51"
SEC"1"
SEC_TYPE"0402"
ROOM"V_SUPER";
"A"
$PN"1"28;
"B"
$PN"2"22;
%"GND"
"1","(-525,4050)","0","mstr_symbols","I76";
;
CDS_LIB"mstr_symbols"
VOLTAGE"0.0V"
SIZE"1B"
BODY_TYPE"PLUMBING"
HDL_POWER"GND";
"A\NAC"22;
%"ADM809"
"1","(200,1350)","0","mstr_analog","I80";
;
POWER_GROUP"GND=GND;"
PART_NUMBER"D23047-001"
MATERIAL"IC"
LOCATION"U1L3"
CDS_LIB"mstr_analog"
CDS_LOCATION"U1L3"
$SEC"1"
PACK_TYPE"SMLF"
CDS_SEC"1"
ROOM"V_SUPER";
"RESET_N \B"
$PN"2"37;
"VCC"
$PN"3"24;
%"CAP_A"
"1","(-300,1250)","0","dev_discrete","I81";
;
CDS_SEC"1"
MATERIAL"X7R"
VOLTAGE"16V"
TOLERANCE"10%"
VALUE"0.1UF"
LOCATION"C1L16"
PART_NUMBER"A36096-030"
PACK_TYPE"0402V"
CDS_LIB"dev_discrete"
ROOM"V_SUPER"
CDS_LOCATION"C1L16"
SEC"1"
SEC_TYPE"0402V";
"B"
$PN"2"23;
"A"
$PN"1"24;
%"GND"
"1","(-300,1050)","0","mstr_symbols","I82";
;
VOLTAGE"0.0V"
SIZE"1B"
CDS_LIB"mstr_symbols"
BODY_TYPE"PLUMBING"
HDL_POWER"GND";
"A\NAC"23;
%"P3V3"
"1","(-300,1500)","0","mstr_symbols","I83";
;
VOLTAGE"3.3V"
CDS_LIB"mstr_symbols"
SIZE"1B"
BODY_TYPE"PLUMBING"
HDL_POWER"P3V3";
"G\NAC"24;
%"ADM809"
"1","(400,3100)","0","mstr_analog","I89";
;
POWER_GROUP"GND=GND;"
PART_NUMBER"D23047-001"
MATERIAL"IC"
LOCATION"U8E2"
ROOM"V_SUPER"
CDS_LOCATION"U8E2"
$SEC"1"
CDS_SEC"1"
CDS_LIB"mstr_analog"
PACK_TYPE"SMLF";
"RESET_N \B"
$PN"2"36;
"VCC"
$PN"3"44;
%"RES"
"1","(1325,3000)","0","mstr_discrete","I90";
;
CDS_SEC"1"
PART_NUMBER"G21796-250"
TOLERANCE"1.0%"
MATERIAL"CHIP"
VALUE"22.1"
LOCATION"R8E7"
WATTAGE"1/16W"
PACK_TYPE"0402"
ROOM"V_SUPER"
SEC_TYPE"0402"
SEC"1"
CDS_LOCATION"R8E7"
CDS_LIB"mstr_discrete";
"B"
$PN"2"39;
"A"
$PN"1"36;
%"CAP_A"
"1","(-300,2950)","0","dev_discrete","I94";
;
CDS_SEC"1"
MATERIAL"X7R"
VOLTAGE"16V"
PACK_TYPE"0402V"
TOLERANCE"10%"
VALUE"0.1UF"
LOCATION"C8E3"
PART_NUMBER"A36096-030"
CDS_LIB"dev_discrete"
CDS_LOCATION"C8E3"
ROOM"V_SUPER"
SEC_TYPE"0402V"
SEC"1";
"B"
$PN"2"25;
"A"
$PN"1"44;
%"GND"
"1","(-300,2750)","0","mstr_symbols","I95";
;
VOLTAGE"0.0V"
CDS_LIB"mstr_symbols"
SIZE"1B"
BODY_TYPE"PLUMBING"
HDL_POWER"GND";
"A\NAC"25;
%"P3V3_RTC_STBY"
"1","(-2200,4875)","0","mstr_symbols","I97";
;
VOLTAGE"3.3V"
ROOM"SB_DECOUPLING"
BOM_COST"SB"
CDS_LIB"mstr_symbols"
BODY_TYPE"PLUMBING"
HDL_POWER"P3V3_RTC_STBY";
"G\NAC"26;
END.
